(kicad_pcb
	(version 20241229)
	(generator "pcbnew")
	(generator_version "9.0")
	(general
		(thickness 1.711)
		(legacy_teardrops no)
	)
	(paper "A4")
	(title_block
		(title "Antmicro Baseboard for Jetson AGX Thor")
		(date "2026-02-18")
		(rev "1.1.0")
		(company "Antmicro Ltd")
		(comment 1 "www.antmicro.com")
		(comment 9 "footprints 1090-1093 of 1170")
	)
	(layers
		(0 "F.Cu" signal)
		(4 "In1.Cu" signal)
		(6 "In2.Cu" signal)
		(8 "In3.Cu" signal)
		(10 "In4.Cu" jumper)
		(12 "In5.Cu" signal)
		(14 "In6.Cu" signal)
		(16 "In7.Cu" signal)
		(18 "In8.Cu" signal)
		(2 "B.Cu" signal)
		(9 "F.Adhes" user "F.Adhesive")
		(11 "B.Adhes" user "B.Adhesive")
		(13 "F.Paste" user)
		(15 "B.Paste" user)
		(5 "F.SilkS" user "F.Silkscreen")
		(7 "B.SilkS" user "B.Silkscreen")
		(1 "F.Mask" user)
		(3 "B.Mask" user)
		(17 "Dwgs.User" user "User.Drawings")
		(19 "Cmts.User" user "User.Comments")
		(21 "Eco1.User" user "User.Eco1")
		(23 "Eco2.User" user "User.Eco2")
		(25 "Edge.Cuts" user)
		(27 "Margin" user)
		(31 "F.CrtYd" user "F.Courtyard")
		(29 "B.CrtYd" user "B.Courtyard")
		(35 "F.Fab" user)
		(33 "B.Fab" user)
	)
	(footprint "antmicro-footprints:SOT-23-6"
		(layer "B.Cu")
		(at 179.25 86.75 90)
		(property "Reference" "U63"
			(at -0.45 -2.65 90)
			(layer "B.SilkS")
			(effects
				(font
					(size 0.7 0.7)
					(thickness 0.15)
				)
				(justify right top mirror)
			)
		)
		(property "Value" "LTC4412IS6"
			(at -1.75 -2.693 90)
			(layer "B.Fab")
			(effects
				(font
					(size 0.7 0.7)
					(thickness 0.15)
				)
				(justify right top mirror)
			)
		)
		(property "Datasheet" "https://www.analog.com/media/en/technical-documentation/data-sheets/4412fb.pdf"
			(at 0 0.057 90)
			(layer "B.Fab")
			(hide yes)
			(effects
				(font
					(size 1.27 1.27)
					(thickness 0.15)
				)
				(justify mirror)
			)
		)
		(property "Description" "Ideal diode controller"
			(at 0 0.057 90)
			(layer "B.Fab")
			(hide yes)
			(effects
				(font
					(size 1.27 1.27)
					(thickness 0.15)
				)
				(justify mirror)
			)
		)
		(property "MPN" "LTC4412IS6#TRMPBF"
			(at 0 0 270)
			(unlocked yes)
			(layer "B.Fab")
			(hide yes)
			(effects
				(font
					(size 1 1)
					(thickness 0.15)
				)
				(justify mirror)
			)
		)
		(property "Manufacturer" "Analog Devices"
			(at 0 0 270)
			(unlocked yes)
			(layer "B.Fab")
			(hide yes)
			(effects
				(font
					(size 1 1)
					(thickness 0.15)
				)
				(justify mirror)
			)
		)
		(property "Author" "Antmicro"
			(at 0 0 270)
			(unlocked yes)
			(layer "B.Fab")
			(hide yes)
			(effects
				(font
					(size 1 1)
					(thickness 0.15)
				)
				(justify mirror)
			)
		)
		(property "License" "Apache-2.0"
			(at 0 0 270)
			(unlocked yes)
			(layer "B.Fab")
			(hide yes)
			(effects
				(font
					(size 1 1)
					(thickness 0.15)
				)
				(justify mirror)
			)
		)
		(sheetname "/Power/")
		(sheetfile "power.kicad_sch")
		(attr smd)
		(fp_line
			(start 1.45 -0.643)
			(end 1.45 -0.343)
			(stroke
				(width 0.12)
				(type solid)
			)
			(layer "B.SilkS")
		)
		(fp_line
			(start 1.3 -0.643)
			(end 1.45 -0.643)
			(stroke
				(width 0.12)
				(type solid)
			)
			(layer "B.SilkS")
		)
		(fp_line
			(start -1.45 -0.643)
			(end -1.45 -0.343)
			(stroke
				(width 0.12)
				(type solid)
			)
			(layer "B.SilkS")
		)
		(fp_line
			(start 1.45 0.757)
			(end 1.45 0.457)
			(stroke
				(width 0.12)
				(type solid)
			)
			(layer "B.SilkS")
		)
		(fp_line
			(start 1.3 0.757)
			(end 1.45 0.757)
			(stroke
				(width 0.12)
				(type solid)
			)
			(layer "B.SilkS")
		)
		(fp_line
			(start -1.3 0.757)
			(end -1.45 0.757)
			(stroke
				(width 0.12)
				(type solid)
			)
			(layer "B.SilkS")
		)
		(fp_line
			(start -1.45 0.757)
			(end -1.45 0.457)
			(stroke
				(width 0.12)
				(type solid)
			)
			(layer "B.SilkS")
		)
		(fp_rect
			(start -1.55 1.85)
			(end 1.55 -1.75)
			(stroke
				(width 0.05)
				(type solid)
			)
			(fill no)
			(layer "B.CrtYd")
		)
		(fp_line
			(start 1.5 -0.643)
			(end -1.5 -0.643)
			(stroke
				(width 0.1)
				(type solid)
			)
			(layer "B.Fab")
		)
		(fp_line
			(start -1.5 -0.643)
			(end -1.5 0.757)
			(stroke
				(width 0.1)
				(type solid)
			)
			(layer "B.Fab")
		)
		(fp_line
			(start 1.5 0.757)
			(end 1.5 -0.643)
			(stroke
				(width 0.1)
				(type solid)
			)
			(layer "B.Fab")
		)
		(fp_line
			(start -1.5 0.757)
			(end 1.5 0.757)
			(stroke
				(width 0.1)
				(type solid)
			)
			(layer "B.Fab")
		)
		(fp_text user "."
			(at -1.05 -2.65 90)
			(layer "B.SilkS")
			(effects
				(font
					(size 1 1)
					(thickness 0.15)
				)
				(justify mirror)
			)
		)
		(fp_text user "Author: Antmicro"
			(at -1.829 -5.25 90)
			(layer "B.Fab")
			(effects
				(font
					(size 0.7 0.7)
					(thickness 0.15)
				)
				(justify right top mirror)
			)
		)
		(fp_text user "${REFERENCE}"
			(at -1.75 -4 90)
			(layer "B.Fab")
			(effects
				(font
					(size 0.7 0.7)
					(thickness 0.15)
				)
				(justify right top mirror)
			)
		)
		(fp_text user "License: Apache-2.0"
			(at -1.75 -6.5 90)
			(layer "B.Fab")
			(effects
				(font
					(size 0.7 0.7)
					(thickness 0.15)
				)
				(justify right top mirror)
			)
		)
		(pad "1" smd roundrect
			(at -0.954 -1.1 90)
			(size 0.55 1)
			(layers "B.Cu" "B.Mask" "B.Paste")
			(roundrect_rratio 0.15)
			(net 904 "+20V")
			(pinfunction "IN")
			(pintype "power_in")
		)
		(pad "2" smd roundrect
			(at -0.003 -1.1 90)
			(size 0.55 1)
			(layers "B.Cu" "B.Mask" "B.Paste")
			(roundrect_rratio 0.15)
			(net 1 "GND")
			(pinfunction "GND")
			(pintype "power_in")
		)
		(pad "3" smd roundrect
			(at 0.947 -1.1 90)
			(size 0.55 1)
			(layers "B.Cu" "B.Mask" "B.Paste")
			(roundrect_rratio 0.15)
			(net 1 "GND")
			(pinfunction "CTL")
			(pintype "input")
		)
		(pad "4" smd roundrect
			(at 0.947 1.214 90)
			(size 0.55 1)
			(layers "B.Cu" "B.Mask" "B.Paste")
			(roundrect_rratio 0.15)
			(net 1226 "unconnected-(U63-STAT-Pad4)")
			(pinfunction "STAT")
			(pintype "output+no_connect")
		)
		(pad "5" smd roundrect
			(at -0.003 1.214 90)
			(size 0.55 1)
			(layers "B.Cu" "B.Mask" "B.Paste")
			(roundrect_rratio 0.15)
			(net 1202 "Net-(Q24-G)")
			(pinfunction "GATE")
			(pintype "output")
		)
		(pad "6" smd roundrect
			(at -0.954 1.214 90)
			(size 0.55 1)
			(layers "B.Cu" "B.Mask" "B.Paste")
			(roundrect_rratio 0.15)
			(net 522 "/Power/USBPD1_HV")
			(pinfunction "SENSE")
			(pintype "input")
		)
	)
	(footprint "antmicro-footprints:C_0402_1005Metric"
		(layer "B.Cu")
		(at 145.1 75.85 -90)
		(descr "Capacitor SMD 0402")
		(tags "capacitor SMD 0402")
		(property "Reference" "C359"
			(at -0.95 -1.6 90)
			(layer "B.SilkS")
			(effects
				(font
					(size 0.7 0.7)
					(thickness 0.15)
				)
				(justify left bottom mirror)
			)
		)
		(property "Value" "C_1u_25V_0402"
			(at -1.022927 -2.155213 90)
			(layer "B.Fab")
			(effects
				(font
					(size 0.7 0.7)
					(thickness 0.15)
				)
				(justify left bottom mirror)
			)
		)
		(property "Datasheet" "https://www.murata.com/products/productdetail?partno=GRM155R61E105KE11%23"
			(at 0 0 90)
			(layer "B.Fab")
			(hide yes)
			(effects
				(font
					(size 1.27 1.27)
					(thickness 0.15)
				)
				(justify mirror)
			)
		)
		(property "Description" "SMD Multilayer Ceramic Capacitor, 1 µF, 25 V, 0402 [1005 Metric], ± 10%, X5R, GRM Series"
			(at 0 0 90)
			(layer "B.Fab")
			(hide yes)
			(effects
				(font
					(size 1.27 1.27)
					(thickness 0.15)
				)
				(justify mirror)
			)
		)
		(property "MPN" "GRM155R61E105KE11J"
			(at 0 0 90)
			(unlocked yes)
			(layer "B.Fab")
			(hide yes)
			(effects
				(font
					(size 1 1)
					(thickness 0.15)
				)
				(justify mirror)
			)
		)
		(property "Manufacturer" "Murata"
			(at 0 0 90)
			(unlocked yes)
			(layer "B.Fab")
			(hide yes)
			(effects
				(font
					(size 1 1)
					(thickness 0.15)
				)
				(justify mirror)
			)
		)
		(property "License" "Apache-2.0"
			(at 0 0 90)
			(unlocked yes)
			(layer "B.Fab")
			(hide yes)
			(effects
				(font
					(size 1 1)
					(thickness 0.15)
				)
				(justify mirror)
			)
		)
		(property "Author" "Antmicro"
			(at 0 0 90)
			(unlocked yes)
			(layer "B.Fab")
			(hide yes)
			(effects
				(font
					(size 1 1)
					(thickness 0.15)
				)
				(justify mirror)
			)
		)
		(property "Val" "1u"
			(at 0 0 90)
			(unlocked yes)
			(layer "B.Fab")
			(hide yes)
			(effects
				(font
					(size 1 1)
					(thickness 0.15)
				)
				(justify mirror)
			)
		)
		(property "Voltage" "25V"
			(at 0 0 90)
			(unlocked yes)
			(layer "B.Fab")
			(hide yes)
			(effects
				(font
					(size 1 1)
					(thickness 0.15)
				)
				(justify mirror)
			)
		)
		(property "Dielectric" "X5R"
			(at 0 0 90)
			(unlocked yes)
			(layer "B.Fab")
			(hide yes)
			(effects
				(font
					(size 1 1)
					(thickness 0.15)
				)
				(justify mirror)
			)
		)
		(sheetname "/SoM_Power/")
		(sheetfile "som_power.kicad_sch")
		(attr smd)
		(fp_poly
			(pts
				(xy -0.925 0.47) (xy 0.925 0.47) (xy 0.925 -0.47) (xy -0.925 -0.47)
			)
			(stroke
				(width 0.05)
				(type default)
			)
			(fill no)
			(layer "B.CrtYd")
		)
		(fp_line
			(start -0.494 0.25)
			(end 0.504 0.25)
			(stroke
				(width 0.15)
				(type solid)
			)
			(layer "B.Fab")
		)
		(fp_line
			(start 0.504 0.25)
			(end 0.504 -0.248)
			(stroke
				(width 0.15)
				(type solid)
			)
			(layer "B.Fab")
		)
		(fp_line
			(start -0.494 -0.248)
			(end -0.494 0.25)
			(stroke
				(width 0.15)
				(type solid)
			)
			(layer "B.Fab")
		)
		(fp_line
			(start 0.504 -0.248)
			(end -0.494 -0.248)
			(stroke
				(width 0.15)
				(type solid)
			)
			(layer "B.Fab")
		)
		(fp_text user "Author: Antmicro"
			(at -0.939 -3.399 90)
			(layer "B.Fab")
			(effects
				(font
					(size 0.7 0.7)
					(thickness 0.15)
				)
				(justify left bottom mirror)
			)
		)
		(fp_text user "${REFERENCE}"
			(at -0.939 -4.599 90)
			(layer "B.Fab")
			(effects
				(font
					(size 0.7 0.7)
					(thickness 0.15)
				)
				(justify left bottom mirror)
			)
		)
		(fp_text user "License: Apache-2.0"
			(at -0.939 -5.799 90)
			(layer "B.Fab")
			(effects
				(font
					(size 0.7 0.7)
					(thickness 0.15)
				)
				(justify left bottom mirror)
			)
		)
		(pad "1" smd roundrect
			(at -0.48 0 270)
			(size 0.59 0.64)
			(layers "B.Cu" "B.Mask" "B.Paste")
			(roundrect_rratio 0.25)
			(net 1 "GND")
			(pintype "passive")
		)
		(pad "2" smd roundrect
			(at 0.48 0 270)
			(size 0.59 0.64)
			(layers "B.Cu" "B.Mask" "B.Paste")
			(roundrect_rratio 0.25)
			(net 12 "SYS_VIN_HV")
			(pintype "passive")
		)
	)
	(footprint "antmicro-footprints:SOT-563"
		(layer "B.Cu")
		(at 223.08 121.67 90)
		(property "Reference" "Q27"
			(at -0.648302 1.21 90)
			(layer "B.SilkS")
			(effects
				(font
					(size 0.7 0.7)
					(thickness 0.15)
				)
				(justify right top mirror)
			)
		)
		(property "Value" "DMC2400UV-7"
			(at 0 -2 90)
			(layer "B.Fab")
			(effects
				(font
					(size 0.7 0.7)
					(thickness 0.15)
				)
				(justify right top mirror)
			)
		)
		(property "Datasheet" "https://www.mouser.com/datasheet/2/115/DIOD_S_A0010038249_1-2543538.pdf"
			(at 0 0 90)
			(layer "B.Fab")
			(hide yes)
			(effects
				(font
					(size 1.27 1.27)
					(thickness 0.15)
				)
				(justify mirror)
			)
		)
		(property "Description" "Dual MOSFET, Complementary N and P Channel, 20 V, 20 V, 1.03 A, 1.03 A, 0.3 ohm"
			(at 0 0 90)
			(layer "B.Fab")
			(hide yes)
			(effects
				(font
					(size 1.27 1.27)
					(thickness 0.15)
				)
				(justify mirror)
			)
		)
		(property "MPN" "DMC2400UV-7"
			(at 0 0 270)
			(unlocked yes)
			(layer "B.Fab")
			(hide yes)
			(effects
				(font
					(size 1 1)
					(thickness 0.15)
				)
				(justify mirror)
			)
		)
		(property "Manufacturer" "Diodes Incorporated"
			(at 0 0 270)
			(unlocked yes)
			(layer "B.Fab")
			(hide yes)
			(effects
				(font
					(size 1 1)
					(thickness 0.15)
				)
				(justify mirror)
			)
		)
		(property "Author" "Antmicro"
			(at 0 0 270)
			(unlocked yes)
			(layer "B.Fab")
			(hide yes)
			(effects
				(font
					(size 1 1)
					(thickness 0.15)
				)
				(justify mirror)
			)
		)
		(property "License" "Apache-2.0"
			(at 0 0 270)
			(unlocked yes)
			(layer "B.Fab")
			(hide yes)
			(effects
				(font
					(size 1 1)
					(thickness 0.15)
				)
				(justify mirror)
			)
		)
		(sheetname "/USB Hub/")
		(sheetfile "usb_hub.kicad_sch")
		(attr smd)
		(fp_line
			(start 0.776 -0.972)
			(end 0.526 -0.972)
			(stroke
				(width 0.15)
				(type solid)
			)
			(layer "B.SilkS")
		)
		(fp_line
			(start -0.778 -0.949)
			(end -0.424 -0.949)
			(stroke
				(width 0.15)
				(type solid)
			)
			(layer "B.SilkS")
		)
		(fp_line
			(start 0.776 -0.776)
			(end 0.776 -0.972)
			(stroke
				(width 0.15)
				(type solid)
			)
			(layer "B.SilkS")
		)
		(fp_line
			(start -0.778 -0.776)
			(end -0.778 -0.949)
			(stroke
				(width 0.15)
				(type solid)
			)
			(layer "B.SilkS")
		)
		(fp_line
			(start 0.776 0.974)
			(end 0.776 0.778)
			(stroke
				(width 0.15)
				(type solid)
			)
			(layer "B.SilkS")
		)
		(fp_line
			(start 0.776 0.974)
			(end 0.526 0.974)
			(stroke
				(width 0.15)
				(type solid)
			)
			(layer "B.SilkS")
		)
		(fp_line
			(start -0.499 0.974)
			(end -0.724 0.778)
			(stroke
				(width 0.15)
				(type solid)
			)
			(layer "B.SilkS")
		)
		(fp_circle
			(center -0.903 0.999)
			(end -0.952 0.95)
			(stroke
				(width 0.15)
				(type solid)
			)
			(fill yes)
			(layer "B.SilkS")
		)
		(fp_rect
			(start 1.19 1.12)
			(end -1.2 -1.1)
			(stroke
				(width 0.05)
				(type solid)
			)
			(fill no)
			(layer "B.CrtYd")
		)
		(fp_line
			(start 0.651 -0.847)
			(end -0.653 -0.847)
			(stroke
				(width 0.15)
				(type solid)
			)
			(layer "B.Fab")
		)
		(fp_line
			(start -0.653 0.678)
			(end -0.653 -0.847)
			(stroke
				(width 0.15)
				(type solid)
			)
			(layer "B.Fab")
		)
		(fp_line
			(start 0.651 0.849)
			(end 0.651 -0.847)
			(stroke
				(width 0.15)
				(type solid)
			)
			(layer "B.Fab")
		)
		(fp_line
			(start -0.453 0.849)
			(end -0.653 0.678)
			(stroke
				(width 0.15)
				(type solid)
			)
			(layer "B.Fab")
		)
		(fp_line
			(start -0.453 0.849)
			(end 0.651 0.849)
			(stroke
				(width 0.15)
				(type solid)
			)
			(layer "B.Fab")
		)
		(fp_text user "Author: Antmicro"
			(at -1.299 -6.124 90)
			(layer "B.Fab")
			(effects
				(font
					(size 0.7 0.7)
					(thickness 0.15)
				)
				(justify right top mirror)
			)
		)
		(fp_text user "${REFERENCE}"
			(at -1.299 -7.323 90)
			(layer "B.Fab")
			(effects
				(font
					(size 0.7 0.7)
					(thickness 0.15)
				)
				(justify right top mirror)
			)
		)
		(fp_text user "License: Apache-2.0"
			(at -1.299 -4.924 90)
			(layer "B.Fab")
			(effects
				(font
					(size 0.7 0.7)
					(thickness 0.15)
				)
				(justify right top mirror)
			)
		)
		(pad "1" smd roundrect
			(at -0.749 0.499 180)
			(size 0.3 0.6)
			(layers "B.Cu" "B.Mask" "B.Paste")
			(roundrect_rratio 0.25)
			(net 1 "GND")
			(pinfunction "S1")
			(pintype "passive")
		)
		(pad "2" smd roundrect
			(at -0.749 -0.001 180)
			(size 0.3 0.6)
			(layers "B.Cu" "B.Mask" "B.Paste")
			(roundrect_rratio 0.25)
			(net 1084 "/USB Hub/DP1_VCONN1")
			(pinfunction "G1")
			(pintype "input")
		)
		(pad "3" smd roundrect
			(at -0.749 -0.497 180)
			(size 0.3 0.6)
			(layers "B.Cu" "B.Mask" "B.Paste")
			(roundrect_rratio 0.25)
			(net 1239 "Net-(D59-A)")
			(pinfunction "D2")
			(pintype "passive")
		)
		(pad "4" smd roundrect
			(at 0.747 -0.497 180)
			(size 0.3 0.6)
			(layers "B.Cu" "B.Mask" "B.Paste")
			(roundrect_rratio 0.25)
			(net 5 "+5V")
			(pinfunction "S2")
			(pintype "passive")
		)
		(pad "5" smd roundrect
			(at 0.747 -0.001 180)
			(size 0.3 0.6)
			(layers "B.Cu" "B.Mask" "B.Paste")
			(roundrect_rratio 0.25)
			(net 1332 "Net-(Q27-D1)")
			(pinfunction "G2")
			(pintype "input")
		)
		(pad "6" smd roundrect
			(at 0.747 0.499 180)
			(size 0.3 0.6)
			(layers "B.Cu" "B.Mask" "B.Paste")
			(roundrect_rratio 0.25)
			(net 1332 "Net-(Q27-D1)")
			(pinfunction "D1")
			(pintype "passive")
		)
	)
	(footprint "antmicro-footprints:C_0402_1005Metric"
		(layer "B.Cu")
		(at 207 65 180)
		(descr "Capacitor SMD 0402")
		(tags "capacitor SMD 0402")
		(property "Reference" "C158"
			(at 0.989001 -0.374 0)
			(layer "B.SilkS")
			(effects
				(font
					(size 0.7 0.7)
					(thickness 0.15)
				)
				(justify left bottom mirror)
			)
		)
		(property "Value" "C_100n_0402"
			(at -1.022927 -2.155213 0)
			(layer "B.Fab")
			(effects
				(font
					(size 0.7 0.7)
					(thickness 0.15)
				)
				(justify left bottom mirror)
			)
		)
		(property "Datasheet" "https://www.murata.com/products/productdetail?partno=GRM155R61H104KE14%23"
			(at 0 0 0)
			(layer "B.Fab")
			(hide yes)
			(effects
				(font
					(size 1.27 1.27)
					(thickness 0.15)
				)
				(justify mirror)
			)
		)
		(property "Description" "SMD Multilayer Ceramic Capacitor, 0.1 µF, 50 V, 0402 [1005 Metric], ± 10%, X5R, GRM Series"
			(at 0 0 0)
			(layer "B.Fab")
			(hide yes)
			(effects
				(font
					(size 1.27 1.27)
					(thickness 0.15)
				)
				(justify mirror)
			)
		)
		(property "Manufacturer" "Murata"
			(at 0 0 0)
			(unlocked yes)
			(layer "B.Fab")
			(hide yes)
			(effects
				(font
					(size 1 1)
					(thickness 0.15)
				)
				(justify mirror)
			)
		)
		(property "MPN" "GRM155R61H104KE14D"
			(at 0 0 0)
			(unlocked yes)
			(layer "B.Fab")
			(hide yes)
			(effects
				(font
					(size 1 1)
					(thickness 0.15)
				)
				(justify mirror)
			)
		)
		(property "Val" "100n"
			(at 0 0 0)
			(unlocked yes)
			(layer "B.Fab")
			(hide yes)
			(effects
				(font
					(size 1 1)
					(thickness 0.15)
				)
				(justify mirror)
			)
		)
		(property "License" "Apache-2.0"
			(at 0 0 0)
			(unlocked yes)
			(layer "B.Fab")
			(hide yes)
			(effects
				(font
					(size 1 1)
					(thickness 0.15)
				)
				(justify mirror)
			)
		)
		(property "Author" "Antmicro"
			(at 0 0 0)
			(unlocked yes)
			(layer "B.Fab")
			(hide yes)
			(effects
				(font
					(size 1 1)
					(thickness 0.15)
				)
				(justify mirror)
			)
		)
		(property "Voltage" "50V"
			(at 0 0 0)
			(unlocked yes)
			(layer "B.Fab")
			(hide yes)
			(effects
				(font
					(size 1 1)
					(thickness 0.15)
				)
				(justify mirror)
			)
		)
		(property "Dielectric" "X5R"
			(at 0 0 0)
			(unlocked yes)
			(layer "B.Fab")
			(hide yes)
			(effects
				(font
					(size 1 1)
					(thickness 0.15)
				)
				(justify mirror)
			)
		)
		(sheetname "/CSI/")
		(sheetfile "csi.kicad_sch")
		(attr smd)
		(fp_poly
			(pts
				(xy -0.925 0.47) (xy -0.925 -0.47) (xy 0.925 -0.47) (xy 0.925 0.47)
			)
			(stroke
				(width 0.05)
				(type default)
			)
			(fill no)
			(layer "B.CrtYd")
		)
		(fp_line
			(start 0.504 0.25)
			(end 0.504 -0.248)
			(stroke
				(width 0.15)
				(type solid)
			)
			(layer "B.Fab")
		)
		(fp_line
			(start 0.504 -0.248)
			(end -0.494 -0.248)
			(stroke
				(width 0.15)
				(type solid)
			)
			(layer "B.Fab")
		)
		(fp_line
			(start -0.494 0.25)
			(end 0.504 0.25)
			(stroke
				(width 0.15)
				(type solid)
			)
			(layer "B.Fab")
		)
		(fp_line
			(start -0.494 -0.248)
			(end -0.494 0.25)
			(stroke
				(width 0.15)
				(type solid)
			)
			(layer "B.Fab")
		)
		(fp_text user "Author: Antmicro"
			(at -0.939 -3.399 0)
			(layer "B.Fab")
			(effects
				(font
					(size 0.7 0.7)
					(thickness 0.15)
				)
				(justify left bottom mirror)
			)
		)
		(fp_text user "${REFERENCE}"
			(at -0.939 -4.599 0)
			(layer "B.Fab")
			(effects
				(font
					(size 0.7 0.7)
					(thickness 0.15)
				)
				(justify left bottom mirror)
			)
		)
		(fp_text user "License: Apache-2.0"
			(at -0.939 -5.799 0)
			(layer "B.Fab")
			(effects
				(font
					(size 0.7 0.7)
					(thickness 0.15)
				)
				(justify left bottom mirror)
			)
		)
		(pad "1" smd roundrect
			(at -0.48 0 180)
			(size 0.59 0.64)
			(layers "B.Cu" "B.Mask" "B.Paste")
			(roundrect_rratio 0.25)
			(net 5 "+5V")
			(pintype "passive")
		)
		(pad "2" smd roundrect
			(at 0.48 0 180)
			(size 0.59 0.64)
			(layers "B.Cu" "B.Mask" "B.Paste")
			(roundrect_rratio 0.25)
			(net 1 "GND")
			(pintype "passive")
		)
	)
)
